# S9S_MB_2U (Grand Teton) — schematic netlist excerpt (pin names and nets, part order shuffled) for the footprints in the layout excerpt that follows; sources: Cadence DE-HDL packaged netlist, KiCad conversion of 03242023_DA0F0TMBIJ0_F0T_Motherboard_J_brd_V01_OCP.brd

PR3787  Q_RES  6.8K 1% EMPTY  pkg 0402LF  page 156 : A = P12V_OCP_UV_1 ; B = P12V_OCP_OV_1
PR1799  Q_RES  0 5% CHIP  pkg 0402LF  page 294 : A = PVCCFA_EHV_CPU1_NC1 ; B = PVCCFA_EHV_CPU1_VDD1

(kicad_pcb
	(version 20260206)
	(generator "pcbnew")
	(generator_version "10.0")
	(general
		(thickness 1.6)
		(legacy_teardrops no)
	)
	(paper "A4")
	(title_block
		(title "03242023_DA0F0TMBIJ0_F0T_Motherboard_J_brd_V01_OCP.brd")
		(comment 1 "Grand Teton / footprints 379-380 of 6105")
	)
	(layers
		(0 "F.Cu" signal "TOP")
		(4 "In1.Cu" signal "GND")
		(6 "In2.Cu" signal "IN1")
		(8 "In3.Cu" signal "GND1")
		(10 "In4.Cu" signal "IN2")
		(12 "In5.Cu" signal "GND2")
		(14 "In6.Cu" signal "IN3")
		(16 "In7.Cu" signal "GND3")
		(18 "In8.Cu" signal "VCC")
		(20 "In9.Cu" signal "VCC1")
		(22 "In10.Cu" signal "GND4")
		(24 "In11.Cu" signal "IN4")
		(26 "In12.Cu" signal "GND5")
		(28 "In13.Cu" signal "IN5")
		(30 "In14.Cu" signal "GND6")
		(32 "In15.Cu" signal "IN6")
		(34 "In16.Cu" signal "GND7")
		(2 "B.Cu" signal "BOTTOM")
		(9 "F.Adhes" user "F.Adhesive")
		(11 "B.Adhes" user "B.Adhesive")
		(13 "F.Paste" user "Package Geometry/Pastemask Top")
		(15 "B.Paste" user "Package Geometry/Pastemask Bottom")
		(5 "F.SilkS" user "Ref Des/Silkscreen Top")
		(7 "B.SilkS" user "Ref Des/Silkscreen Bottom")
		(1 "F.Mask" user "Board Geometry/Soldermask Top")
		(3 "B.Mask" user "Board Geometry/Soldermask Bottom")
		(17 "Dwgs.User" user "User.Drawings")
		(19 "Cmts.User" user "User.Comments")
		(21 "Eco1.User" user "User.Eco1")
		(23 "Eco2.User" user "User.Eco2")
		(25 "Edge.Cuts" user "Board Geometry/Outline")
		(27 "Margin" user)
		(31 "F.CrtYd" user "Package Geometry/Place Bound Top")
		(29 "B.CrtYd" user "Package Geometry/Place Bound Bottom")
		(35 "F.Fab" user "Ref Des/Assembly Top")
		(33 "B.Fab" user "Ref Des/Assembly Bottom")
	)
	(footprint ""
		(layer "F.Cu")
		(at 51.10988 -170.576748 -90)
		(property "Reference" "PR1799"
			(at 0 0 270)
			(layer "F.SilkS")
			(hide yes)
			(effects
				(font
					(size 1.27 1.27)
				)
			)
		)
		(property "Value" ""
			(at 0 0 270)
			(layer "F.Fab")
			(effects
				(font
					(size 1.27 1.27)
				)
			)
		)
		(duplicate_pad_numbers_are_jumpers no)
		(fp_line
			(start -0.7874 0.4064)
			(end -0.7874 -0.4064)
			(stroke
				(width 0.1524)
				(type default)
			)
			(layer "F.SilkS")
		)
		(fp_line
			(start 0.7874 0.4064)
			(end -0.7874 0.4064)
			(stroke
				(width 0.1524)
				(type default)
			)
			(layer "F.SilkS")
		)
		(fp_line
			(start -0.7874 -0.4064)
			(end 0.7874 -0.4064)
			(stroke
				(width 0.1524)
				(type default)
			)
			(layer "F.SilkS")
		)
		(fp_line
			(start 0.7874 -0.4064)
			(end 0.7874 0.4064)
			(stroke
				(width 0.1524)
				(type default)
			)
			(layer "F.SilkS")
		)
		(fp_line
			(start -0.67945 0.3048)
			(end -0.67945 -0.305054)
			(stroke
				(width 0.1)
				(type default)
			)
			(layer "F.Fab")
		)
		(fp_line
			(start -0.12065 0.3048)
			(end -0.67945 0.3048)
			(stroke
				(width 0.1)
				(type default)
			)
			(layer "F.Fab")
		)
		(fp_line
			(start 0.120396 0.3048)
			(end 0.120396 0.2794)
			(stroke
				(width 0.1)
				(type default)
			)
			(layer "F.Fab")
		)
		(fp_line
			(start 0.67945 0.3048)
			(end 0.120396 0.3048)
			(stroke
				(width 0.1)
				(type default)
			)
			(layer "F.Fab")
		)
		(fp_line
			(start -0.12065 0.2794)
			(end -0.12065 0.3048)
			(stroke
				(width 0.1)
				(type default)
			)
			(layer "F.Fab")
		)
		(fp_line
			(start 0.120396 0.2794)
			(end -0.12065 0.2794)
			(stroke
				(width 0.1)
				(type default)
			)
			(layer "F.Fab")
		)
		(fp_line
			(start -0.12065 -0.2794)
			(end 0.12065 -0.2794)
			(stroke
				(width 0.1)
				(type default)
			)
			(layer "F.Fab")
		)
		(fp_line
			(start 0.12065 -0.2794)
			(end 0.12065 -0.3048)
			(stroke
				(width 0.1)
				(type default)
			)
			(layer "F.Fab")
		)
		(fp_line
			(start 0.12065 -0.3048)
			(end 0.67945 -0.3048)
			(stroke
				(width 0.1)
				(type default)
			)
			(layer "F.Fab")
		)
		(fp_line
			(start 0.67945 -0.3048)
			(end 0.67945 0.3048)
			(stroke
				(width 0.1)
				(type default)
			)
			(layer "F.Fab")
		)
		(fp_line
			(start -0.67945 -0.305054)
			(end -0.12065 -0.305054)
			(stroke
				(width 0.1)
				(type default)
			)
			(layer "F.Fab")
		)
		(fp_line
			(start -0.12065 -0.305054)
			(end -0.12065 -0.2794)
			(stroke
				(width 0.1)
				(type default)
			)
			(layer "F.Fab")
		)
		(pad "1" smd circle
			(at -0.40005 0 270)
			(size 0 0)
			(layers "F.Cu" "F.Mask" "F.Paste")
			(net "PVCCFA_EHV_CPU1_NC1")
		)
		(pad "2" smd circle
			(at 0.40005 0 270)
			(size 0 0)
			(layers "F.Cu" "F.Mask" "F.Paste")
			(net "PVCCFA_EHV_CPU1_VDD1")
		)
	)
	(footprint ""
		(layer "F.Cu")
		(at 448.980052 -18.063464 -90)
		(property "Reference" "PR3787"
			(at 0 0 270)
			(layer "F.SilkS")
			(hide yes)
			(effects
				(font
					(size 1.27 1.27)
				)
			)
		)
		(property "Value" ""
			(at 0 0 270)
			(layer "F.Fab")
			(effects
				(font
					(size 1.27 1.27)
				)
			)
		)
		(duplicate_pad_numbers_are_jumpers no)
		(fp_line
			(start -0.7874 0.4064)
			(end -0.7874 -0.4064)
			(stroke
				(width 0.1524)
				(type default)
			)
			(layer "F.SilkS")
		)
		(fp_line
			(start 0.7874 0.4064)
			(end -0.7874 0.4064)
			(stroke
				(width 0.1524)
				(type default)
			)
			(layer "F.SilkS")
		)
		(fp_line
			(start -0.7874 -0.4064)
			(end 0.7874 -0.4064)
			(stroke
				(width 0.1524)
				(type default)
			)
			(layer "F.SilkS")
		)
		(fp_line
			(start 0.7874 -0.4064)
			(end 0.7874 0.4064)
			(stroke
				(width 0.1524)
				(type default)
			)
			(layer "F.SilkS")
		)
		(fp_line
			(start -0.67945 0.3048)
			(end -0.67945 -0.305054)
			(stroke
				(width 0.1)
				(type default)
			)
			(layer "F.Fab")
		)
		(fp_line
			(start -0.12065 0.3048)
			(end -0.67945 0.3048)
			(stroke
				(width 0.1)
				(type default)
			)
			(layer "F.Fab")
		)
		(fp_line
			(start 0.120396 0.3048)
			(end 0.120396 0.2794)
			(stroke
				(width 0.1)
				(type default)
			)
			(layer "F.Fab")
		)
		(fp_line
			(start 0.67945 0.3048)
			(end 0.120396 0.3048)
			(stroke
				(width 0.1)
				(type default)
			)
			(layer "F.Fab")
		)
		(fp_line
			(start -0.12065 0.2794)
			(end -0.12065 0.3048)
			(stroke
				(width 0.1)
				(type default)
			)
			(layer "F.Fab")
		)
		(fp_line
			(start 0.120396 0.2794)
			(end -0.12065 0.2794)
			(stroke
				(width 0.1)
				(type default)
			)
			(layer "F.Fab")
		)
		(fp_line
			(start -0.12065 -0.2794)
			(end 0.12065 -0.2794)
			(stroke
				(width 0.1)
				(type default)
			)
			(layer "F.Fab")
		)
		(fp_line
			(start 0.12065 -0.2794)
			(end 0.12065 -0.3048)
			(stroke
				(width 0.1)
				(type default)
			)
			(layer "F.Fab")
		)
		(fp_line
			(start 0.12065 -0.3048)
			(end 0.67945 -0.3048)
			(stroke
				(width 0.1)
				(type default)
			)
			(layer "F.Fab")
		)
		(fp_line
			(start 0.67945 -0.3048)
			(end 0.67945 0.3048)
			(stroke
				(width 0.1)
				(type default)
			)
			(layer "F.Fab")
		)
		(fp_line
			(start -0.67945 -0.305054)
			(end -0.12065 -0.305054)
			(stroke
				(width 0.1)
				(type default)
			)
			(layer "F.Fab")
		)
		(fp_line
			(start -0.12065 -0.305054)
			(end -0.12065 -0.2794)
			(stroke
				(width 0.1)
				(type default)
			)
			(layer "F.Fab")
		)
		(pad "1" smd circle
			(at -0.40005 0 270)
			(size 0 0)
			(layers "F.Cu" "F.Mask" "F.Paste")
			(net "P12V_OCP_UV_1")
		)
		(pad "2" smd circle
			(at 0.40005 0 270)
			(size 0 0)
			(layers "F.Cu" "F.Mask" "F.Paste")
			(net "P12V_OCP_OV_1")
		)
	)
)
